(kicad_pcb
	(version 20260206)
	(generator "pcbnew")
	(generator_version "10.0")
	(general
		(thickness 1.6)
		(legacy_teardrops no)
	)
	(paper "A4")
	(title_block
		(title "Wiwynn_Tioga_Pass_MB.brd")
		(comment 1 "Tioga Pass / footprints 1111-1117 of 4770")
	)
	(layers
		(0 "F.Cu" signal "TOP")
		(4 "In1.Cu" signal "L2GND")
		(6 "In2.Cu" signal "L3")
		(8 "In3.Cu" signal "L4GND")
		(10 "In4.Cu" signal "L5")
		(12 "In5.Cu" signal "L6GND")
		(14 "In6.Cu" signal "L7VCC")
		(16 "In7.Cu" signal "L8VCC")
		(18 "In8.Cu" signal "L9GND")
		(20 "In9.Cu" signal "L10")
		(22 "In10.Cu" signal "L11GND")
		(24 "In11.Cu" signal "L12")
		(26 "In12.Cu" signal "L13GND")
		(2 "B.Cu" signal "BOTTOM")
		(9 "F.Adhes" user "F.Adhesive")
		(11 "B.Adhes" user "B.Adhesive")
		(13 "F.Paste" user "Package Geometry/Pastemask Top")
		(15 "B.Paste" user "Package Geometry/Pastemask Bottom")
		(5 "F.SilkS" user "Ref Des/Silkscreen Top")
		(7 "B.SilkS" user "Ref Des/Silkscreen Bottom")
		(1 "F.Mask" user "Board Geometry/Soldermask Top")
		(3 "B.Mask" user "Board Geometry/Soldermask Bottom")
		(17 "Dwgs.User" user "User.Drawings")
		(19 "Cmts.User" user "User.Comments")
		(21 "Eco1.User" user "User.Eco1")
		(23 "Eco2.User" user "User.Eco2")
		(25 "Edge.Cuts" user "Board Geometry/Outline")
		(27 "Margin" user)
		(31 "F.CrtYd" user "Package Geometry/Place Bound Top")
		(29 "B.CrtYd" user "Package Geometry/Place Bound Bottom")
		(35 "F.Fab" user "Ref Des/Assembly Top")
		(33 "B.Fab" user "Ref Des/Assembly Bottom")
	)
	(footprint ""
		(layer "F.Cu")
		(at 350.407224 -4.167378 180)
		(property "Reference" "C7G31"
			(at 0 0 180)
			(layer "F.SilkS")
			(hide yes)
			(effects
				(font
					(size 1.27 1.27)
				)
			)
		)
		(property "Value" ""
			(at 0 0 180)
			(layer "F.Fab")
			(effects
				(font
					(size 1.27 1.27)
				)
			)
		)
		(duplicate_pad_numbers_are_jumpers no)
		(fp_poly
			(pts
				(xy 0.3048 -0.1016) (xy 0.3048 0.9906) (xy -0.3048 0.9906) (xy -0.3048 -0.1016)
			)
			(stroke
				(width 0)
				(type default)
			)
			(fill no)
			(layer "F.CrtYd")
		)
		(fp_line
			(start 0.3048 0.9906)
			(end 0.3048 -0.1016)
			(stroke
				(width 0.1)
				(type default)
			)
			(layer "F.Fab")
		)
		(fp_line
			(start 0.3048 -0.1016)
			(end -0.3048 -0.1016)
			(stroke
				(width 0.1)
				(type default)
			)
			(layer "F.Fab")
		)
		(fp_line
			(start -0.3048 0.9906)
			(end 0.3048 0.9906)
			(stroke
				(width 0.1)
				(type default)
			)
			(layer "F.Fab")
		)
		(fp_line
			(start -0.3048 -0.1016)
			(end -0.3048 0.9906)
			(stroke
				(width 0.1)
				(type default)
			)
			(layer "F.Fab")
		)
		(pad "1" smd rect
			(at 0 0 180)
			(size 0.508 0.508)
			(layers "F.Cu" "F.Mask" "F.Paste")
			(net "VR_PVDDQ_ABC_PH1_BOOT")
		)
		(pad "2" smd rect
			(at 0 0.889 180)
			(size 0.508 0.508)
			(layers "F.Cu" "F.Mask" "F.Paste")
			(net "VR_PVDDQ_ABC_PH1_PHASE")
		)
		(zone
			(layer "F.Cu")
			(hatch none 0.5)
			(connect_pads
				(clearance 0)
			)
			(min_thickness 0.25)
			(keepout
				(tracks not_allowed)
				(vias allowed)
				(pads allowed)
				(copperpour not_allowed)
				(footprints allowed)
			)
			(placement
				(enabled no)
				(sheetname "")
			)
			(fill
				(thermal_gap 0.5)
				(thermal_bridge_width 0.5)
				(island_removal_mode 0)
			)
			(polygon
				(pts
					(xy 350.661224 -4.802378) (xy 350.153224 -4.802378) (xy 350.153224 -4.421378) (xy 350.661224 -4.421378)
				)
			)
		)
		(zone
			(layer "F.Cu")
			(hatch none 0.5)
			(connect_pads
				(clearance 0)
			)
			(min_thickness 0.25)
			(keepout
				(tracks allowed)
				(vias not_allowed)
				(pads allowed)
				(copperpour not_allowed)
				(footprints allowed)
			)
			(placement
				(enabled no)
				(sheetname "")
			)
			(fill
				(thermal_gap 0.5)
				(thermal_bridge_width 0.5)
				(island_removal_mode 0)
			)
			(polygon
				(pts
					(xy 350.661224 -4.421378) (xy 350.153224 -4.421378) (xy 350.153224 -4.802378) (xy 350.661224 -4.802378)
				)
			)
		)
	)
	(footprint ""
		(layer "F.Cu")
		(at 178.181 -58.166 -90)
		(property "Reference" "C4E23"
			(at 0 0 270)
			(layer "F.SilkS")
			(hide yes)
			(effects
				(font
					(size 1.27 1.27)
				)
			)
		)
		(property "Value" ""
			(at 0 0 270)
			(layer "F.Fab")
			(effects
				(font
					(size 1.27 1.27)
				)
			)
		)
		(duplicate_pad_numbers_are_jumpers no)
		(fp_poly
			(pts
				(xy 0.3048 -0.1016) (xy 0.3048 0.9906) (xy -0.3048 0.9906) (xy -0.3048 -0.1016)
			)
			(stroke
				(width 0)
				(type default)
			)
			(fill no)
			(layer "F.CrtYd")
		)
		(fp_line
			(start -0.3048 0.9906)
			(end 0.3048 0.9906)
			(stroke
				(width 0.1)
				(type default)
			)
			(layer "F.Fab")
		)
		(fp_line
			(start 0.3048 0.9906)
			(end 0.3048 -0.1016)
			(stroke
				(width 0.1)
				(type default)
			)
			(layer "F.Fab")
		)
		(fp_line
			(start -0.3048 -0.1016)
			(end -0.3048 0.9906)
			(stroke
				(width 0.1)
				(type default)
			)
			(layer "F.Fab")
		)
		(fp_line
			(start 0.3048 -0.1016)
			(end -0.3048 -0.1016)
			(stroke
				(width 0.1)
				(type default)
			)
			(layer "F.Fab")
		)
		(pad "1" smd rect
			(at 0 0 270)
			(size 0.508 0.508)
			(layers "F.Cu" "F.Mask" "F.Paste")
			(net "P5V_STBY")
		)
		(pad "2" smd rect
			(at 0 0.889 270)
			(size 0.508 0.508)
			(layers "F.Cu" "F.Mask" "F.Paste")
			(net "GND")
		)
		(zone
			(layer "F.Cu")
			(hatch none 0.5)
			(connect_pads
				(clearance 0)
			)
			(min_thickness 0.25)
			(keepout
				(tracks not_allowed)
				(vias allowed)
				(pads allowed)
				(copperpour not_allowed)
				(footprints allowed)
			)
			(placement
				(enabled no)
				(sheetname "")
			)
			(fill
				(thermal_gap 0.5)
				(thermal_bridge_width 0.5)
				(island_removal_mode 0)
			)
			(polygon
				(pts
					(xy 177.546 -58.42) (xy 177.546 -57.912) (xy 177.927 -57.912) (xy 177.927 -58.42)
				)
			)
		)
		(zone
			(layer "F.Cu")
			(hatch none 0.5)
			(connect_pads
				(clearance 0)
			)
			(min_thickness 0.25)
			(keepout
				(tracks allowed)
				(vias not_allowed)
				(pads allowed)
				(copperpour not_allowed)
				(footprints allowed)
			)
			(placement
				(enabled no)
				(sheetname "")
			)
			(fill
				(thermal_gap 0.5)
				(thermal_bridge_width 0.5)
				(island_removal_mode 0)
			)
			(polygon
				(pts
					(xy 177.927 -58.42) (xy 177.927 -57.912) (xy 177.546 -57.912) (xy 177.546 -58.42)
				)
			)
		)
	)
	(footprint ""
		(layer "F.Cu")
		(at 0 0 90)
		(property "Reference" "RM1G1"
			(at 0 0 90)
			(layer "F.SilkS")
			(hide yes)
			(effects
				(font
					(size 1.27 1.27)
				)
			)
		)
		(property "Value" "*"
			(at 7.0612 1.3462 90)
			(unlocked yes)
			(layer "F.Fab")
			(hide yes)
			(effects
				(font
					(size 1.27 1.016)
					(thickness 0.1524)
				)
			)
		)
		(property "Device Type" "STFT363B238R224H453-GP_DISCRETA"
			(at 7.0612 -0.1778 90)
			(unlocked yes)
			(layer "F.Fab")
			(hide yes)
			(effects
				(font
					(size 1.27 1.016)
					(thickness 0.1524)
				)
			)
		)
		(duplicate_pad_numbers_are_jumpers no)
		(fp_circle
			(center 0 0)
			(end 0 5.3594)
			(stroke
				(width 0.3048)
				(type default)
			)
			(fill no)
			(layer "F.SilkS")
		)
		(fp_poly
			(pts
				(arc
					(start 0 3.5306)
					(mid 0 -3.5306)
					(end 0 3.5306)
				)
			)
			(stroke
				(width 0)
				(type default)
			)
			(fill no)
			(layer "B.CrtYd")
		)
		(fp_poly
			(pts
				(arc
					(start 0 5.0038)
					(mid 0 -5.0038)
					(end 0 5.0038)
				)
			)
			(stroke
				(width 0)
				(type default)
			)
			(fill no)
			(layer "F.CrtYd")
		)
		(fp_poly
			(pts
				(arc
					(start 5.5118 0.00635)
					(mid -5.511804 0)
					(end 5.5118 -0.00635)
				)
				(arc
					(start 5.0038 -0.00635)
					(mid -5.003804 0)
					(end 5.0038 0.00635)
				)
			)
			(stroke
				(width 0)
				(type default)
			)
			(fill no)
			(layer "F.CrtYd")
		)
		(fp_poly
			(pts
				(arc
					(start 0 3.5306)
					(mid 0 -3.5306)
					(end 0 3.5306)
				)
			)
			(stroke
				(width 0)
				(type default)
			)
			(fill no)
			(layer "B.Fab")
		)
		(fp_poly
			(pts
				(arc
					(start 0 5.5118)
					(mid 0 -5.5118)
					(end 0 5.5118)
				)
			)
			(stroke
				(width 0)
				(type default)
			)
			(fill no)
			(layer "F.Fab")
		)
		(pad "1" thru_hole circle
			(at 0 0 90)
			(size 9.2202 9.2202)
			(drill 5.6896)
			(layers "*.Cu" "*.Mask")
			(remove_unused_layers no)
			(net "GND")
			(clearance -1.2573)
			(thermal_gap 0.3302)
			(padstack
				(mode front_inner_back)
				(layer "Inner"
					(shape circle)
					(size 6.0452 6.0452)
					(clearance 0.3302)
				)
				(layer "B.Cu"
					(shape circle)
					(size 6.0452 6.0452)
					(clearance 0.3302)
				)
			)
		)
	)
	(footprint ""
		(layer "F.Cu")
		(at 411.975046 -22.196552)
		(property "Reference" "C25W8"
			(at -0.8382 -0.67818 0)
			(unlocked yes)
			(layer "F.SilkS")
			(effects
				(font
					(size 0.4064 0.254)
					(thickness 0.1524)
				)
				(justify left)
			)
		)
		(property "Value" ""
			(at 0 0 0)
			(layer "F.Fab")
			(effects
				(font
					(size 1.27 1.27)
				)
			)
		)
		(duplicate_pad_numbers_are_jumpers no)
		(fp_poly
			(pts
				(xy 0.3048 -0.1016) (xy 0.3048 0.9906) (xy -0.3048 0.9906) (xy -0.3048 -0.1016)
			)
			(stroke
				(width 0)
				(type default)
			)
			(fill no)
			(layer "F.CrtYd")
		)
		(fp_line
			(start -0.3048 -0.1016)
			(end -0.3048 0.9906)
			(stroke
				(width 0.1)
				(type default)
			)
			(layer "F.Fab")
		)
		(fp_line
			(start -0.3048 0.9906)
			(end 0.3048 0.9906)
			(stroke
				(width 0.1)
				(type default)
			)
			(layer "F.Fab")
		)
		(fp_line
			(start 0.3048 -0.1016)
			(end -0.3048 -0.1016)
			(stroke
				(width 0.1)
				(type default)
			)
			(layer "F.Fab")
		)
		(fp_line
			(start 0.3048 0.9906)
			(end 0.3048 -0.1016)
			(stroke
				(width 0.1)
				(type default)
			)
			(layer "F.Fab")
		)
		(pad "1" smd rect
			(at 0 0)
			(size 0.508 0.508)
			(layers "F.Cu" "F.Mask" "F.Paste")
			(net "P3V3_STBY_BMC_ADCVREFN")
		)
		(pad "2" smd rect
			(at 0 0.889)
			(size 0.508 0.508)
			(layers "F.Cu" "F.Mask" "F.Paste")
			(net "GND")
		)
		(zone
			(layer "F.Cu")
			(hatch none 0.5)
			(connect_pads
				(clearance 0)
			)
			(min_thickness 0.25)
			(keepout
				(tracks allowed)
				(vias not_allowed)
				(pads allowed)
				(copperpour not_allowed)
				(footprints allowed)
			)
			(placement
				(enabled no)
				(sheetname "")
			)
			(fill
				(thermal_gap 0.5)
				(thermal_bridge_width 0.5)
				(island_removal_mode 0)
			)
			(polygon
				(pts
					(xy 411.721046 -21.942552) (xy 412.229046 -21.942552) (xy 412.229046 -21.561552) (xy 411.721046 -21.561552)
				)
			)
		)
		(zone
			(layer "F.Cu")
			(hatch none 0.5)
			(connect_pads
				(clearance 0)
			)
			(min_thickness 0.25)
			(keepout
				(tracks not_allowed)
				(vias allowed)
				(pads allowed)
				(copperpour not_allowed)
				(footprints allowed)
			)
			(placement
				(enabled no)
				(sheetname "")
			)
			(fill
				(thermal_gap 0.5)
				(thermal_bridge_width 0.5)
				(island_removal_mode 0)
			)
			(polygon
				(pts
					(xy 411.721046 -21.561552) (xy 412.229046 -21.561552) (xy 412.229046 -21.942552) (xy 411.721046 -21.942552)
				)
			)
		)
	)
	(footprint ""
		(layer "F.Cu")
		(at 420.7256 -86.4235)
		(property "Reference" "C8D2"
			(at 0 0 0)
			(layer "F.SilkS")
			(hide yes)
			(effects
				(font
					(size 1.27 1.27)
				)
			)
		)
		(property "Value" ""
			(at 0 0 0)
			(layer "F.Fab")
			(effects
				(font
					(size 1.27 1.27)
				)
			)
		)
		(duplicate_pad_numbers_are_jumpers no)
		(fp_poly
			(pts
				(xy 0.3048 -0.1016) (xy 0.3048 0.9906) (xy -0.3048 0.9906) (xy -0.3048 -0.1016)
			)
			(stroke
				(width 0)
				(type default)
			)
			(fill no)
			(layer "F.CrtYd")
		)
		(fp_line
			(start -0.3048 -0.1016)
			(end -0.3048 0.9906)
			(stroke
				(width 0.1)
				(type default)
			)
			(layer "F.Fab")
		)
		(fp_line
			(start -0.3048 0.9906)
			(end 0.3048 0.9906)
			(stroke
				(width 0.1)
				(type default)
			)
			(layer "F.Fab")
		)
		(fp_line
			(start 0.3048 -0.1016)
			(end -0.3048 -0.1016)
			(stroke
				(width 0.1)
				(type default)
			)
			(layer "F.Fab")
		)
		(fp_line
			(start 0.3048 0.9906)
			(end 0.3048 -0.1016)
			(stroke
				(width 0.1)
				(type default)
			)
			(layer "F.Fab")
		)
		(pad "1" smd rect
			(at 0 0)
			(size 0.508 0.508)
			(layers "F.Cu" "F.Mask" "F.Paste")
			(net "P3V3_STBY")
		)
		(pad "2" smd rect
			(at 0 0.889)
			(size 0.508 0.508)
			(layers "F.Cu" "F.Mask" "F.Paste")
			(net "GND")
		)
		(zone
			(layer "F.Cu")
			(hatch none 0.5)
			(connect_pads
				(clearance 0)
			)
			(min_thickness 0.25)
			(keepout
				(tracks allowed)
				(vias not_allowed)
				(pads allowed)
				(copperpour not_allowed)
				(footprints allowed)
			)
			(placement
				(enabled no)
				(sheetname "")
			)
			(fill
				(thermal_gap 0.5)
				(thermal_bridge_width 0.5)
				(island_removal_mode 0)
			)
			(polygon
				(pts
					(xy 420.4716 -86.1695) (xy 420.9796 -86.1695) (xy 420.9796 -85.7885) (xy 420.4716 -85.7885)
				)
			)
		)
		(zone
			(layer "F.Cu")
			(hatch none 0.5)
			(connect_pads
				(clearance 0)
			)
			(min_thickness 0.25)
			(keepout
				(tracks not_allowed)
				(vias allowed)
				(pads allowed)
				(copperpour not_allowed)
				(footprints allowed)
			)
			(placement
				(enabled no)
				(sheetname "")
			)
			(fill
				(thermal_gap 0.5)
				(thermal_bridge_width 0.5)
				(island_removal_mode 0)
			)
			(polygon
				(pts
					(xy 420.4716 -85.7885) (xy 420.9796 -85.7885) (xy 420.9796 -86.1695) (xy 420.4716 -86.1695)
				)
			)
		)
	)
	(footprint ""
		(layer "F.Cu")
		(at 170.9166 -8.6614)
		(property "Reference" "R4G5"
			(at 0 0 0)
			(layer "F.SilkS")
			(hide yes)
			(effects
				(font
					(size 1.27 1.27)
				)
			)
		)
		(property "Value" ""
			(at 0 0 0)
			(layer "F.Fab")
			(effects
				(font
					(size 1.27 1.27)
				)
			)
		)
		(duplicate_pad_numbers_are_jumpers no)
		(fp_rect
			(start -0.2794 0.9906)
			(end 0.2794 -0.1016)
			(stroke
				(width 0)
				(type default)
			)
			(fill no)
			(layer "F.CrtYd")
		)
		(fp_line
			(start -0.2794 -0.1016)
			(end -0.2794 0.9906)
			(stroke
				(width 0.1)
				(type default)
			)
			(layer "F.Fab")
		)
		(fp_line
			(start -0.2794 0.9906)
			(end 0.2794 0.9906)
			(stroke
				(width 0.1)
				(type default)
			)
			(layer "F.Fab")
		)
		(fp_line
			(start 0.2794 -0.1016)
			(end -0.2794 -0.1016)
			(stroke
				(width 0.1)
				(type default)
			)
			(layer "F.Fab")
		)
		(fp_line
			(start 0.2794 0.9906)
			(end 0.2794 -0.1016)
			(stroke
				(width 0.1)
				(type default)
			)
			(layer "F.Fab")
		)
		(pad "1" smd rect
			(at 0 0)
			(size 0.508 0.508)
			(layers "F.Cu" "F.Mask" "F.Paste")
			(net "FM_PVPP_CPU1_EN")
		)
		(pad "2" smd rect
			(at 0 0.889)
			(size 0.508 0.508)
			(layers "F.Cu" "F.Mask" "F.Paste")
			(net "GND")
		)
		(zone
			(layer "F.Cu")
			(hatch none 0.5)
			(connect_pads
				(clearance 0)
			)
			(min_thickness 0.25)
			(keepout
				(tracks not_allowed)
				(vias allowed)
				(pads allowed)
				(copperpour not_allowed)
				(footprints allowed)
			)
			(placement
				(enabled no)
				(sheetname "")
			)
			(fill
				(thermal_gap 0.5)
				(thermal_bridge_width 0.5)
				(island_removal_mode 0)
			)
			(polygon
				(pts
					(xy 170.6626 -8.0264) (xy 171.1706 -8.0264) (xy 171.1706 -8.4074) (xy 170.6626 -8.4074)
				)
			)
		)
		(zone
			(layer "F.Cu")
			(hatch none 0.5)
			(connect_pads
				(clearance 0)
			)
			(min_thickness 0.25)
			(keepout
				(tracks allowed)
				(vias not_allowed)
				(pads allowed)
				(copperpour not_allowed)
				(footprints allowed)
			)
			(placement
				(enabled no)
				(sheetname "")
			)
			(fill
				(thermal_gap 0.5)
				(thermal_bridge_width 0.5)
				(island_removal_mode 0)
			)
			(polygon
				(pts
					(xy 170.6626 -8.0264) (xy 171.1706 -8.0264) (xy 171.1706 -8.4074) (xy 170.6626 -8.4074)
				)
			)
		)
	)
	(footprint ""
		(layer "F.Cu")
		(at 29.083 -92.3798 -90)
		(property "Reference" "C1C26"
			(at 0 0 270)
			(layer "F.SilkS")
			(hide yes)
			(effects
				(font
					(size 1.27 1.27)
				)
			)
		)
		(property "Value" ""
			(at 0 0 270)
			(layer "F.Fab")
			(effects
				(font
					(size 1.27 1.27)
				)
			)
		)
		(duplicate_pad_numbers_are_jumpers no)
		(fp_rect
			(start 0.3048 -0.1016)
			(end -0.3048 0.9906)
			(stroke
				(width 0)
				(type default)
			)
			(fill no)
			(layer "F.CrtYd")
		)
		(fp_line
			(start -0.3048 0.9906)
			(end 0.3048 0.9906)
			(stroke
				(width 0.1)
				(type default)
			)
			(layer "F.Fab")
		)
		(fp_line
			(start 0.3048 0.9906)
			(end 0.3048 -0.1016)
			(stroke
				(width 0.1)
				(type default)
			)
			(layer "F.Fab")
		)
		(fp_line
			(start -0.3048 -0.1016)
			(end -0.3048 0.9906)
			(stroke
				(width 0.1)
				(type default)
			)
			(layer "F.Fab")
		)
		(fp_line
			(start 0.3048 -0.1016)
			(end -0.3048 -0.1016)
			(stroke
				(width 0.1)
				(type default)
			)
			(layer "F.Fab")
		)
		(pad "1" smd rect
			(at 0 0 270)
			(size 0.508 0.508)
			(layers "F.Cu" "F.Mask" "F.Paste")
			(net "VR_FET_SW_P12V_STBY_PVCCIN_CPU1")
		)
		(pad "2" smd rect
			(at 0 0.889 270)
			(size 0.508 0.508)
			(layers "F.Cu" "F.Mask" "F.Paste")
			(net "GND")
		)
		(zone
			(layer "F.Cu")
			(hatch none 0.5)
			(connect_pads
				(clearance 0)
			)
			(min_thickness 0.25)
			(keepout
				(tracks allowed)
				(vias not_allowed)
				(pads allowed)
				(copperpour not_allowed)
				(footprints allowed)
			)
			(placement
				(enabled no)
				(sheetname "")
			)
			(fill
				(thermal_gap 0.5)
				(thermal_bridge_width 0.5)
				(island_removal_mode 0)
			)
			(polygon
				(pts
					(xy 28.829 -92.1258) (xy 28.829 -92.6338) (xy 28.448 -92.6338) (xy 28.448 -92.1258)
				)
			)
		)
		(zone
			(layer "F.Cu")
			(hatch none 0.5)
			(connect_pads
				(clearance 0)
			)
			(min_thickness 0.25)
			(keepout
				(tracks not_allowed)
				(vias allowed)
				(pads allowed)
				(copperpour not_allowed)
				(footprints allowed)
			)
			(placement
				(enabled no)
				(sheetname "")
			)
			(fill
				(thermal_gap 0.5)
				(thermal_bridge_width 0.5)
				(island_removal_mode 0)
			)
			(polygon
				(pts
					(xy 28.829 -92.1258) (xy 28.829 -92.6338) (xy 28.448 -92.6338) (xy 28.448 -92.1258)
				)
			)
		)
	)
)
